# T6G (Grand Teton) — schematic netlist excerpt (pin names and nets, part order shuffled) for the footprints in the layout excerpt that follows; sources: Cadence DE-HDL packaged netlist, KiCad conversion of 04192023_DAF0TMB3IC0_F0TG_MB_C_brd_V02_OCP.brd

PR4007  Q_RES  10K 1% CHIP  pkg 0402LF  page 152 : A = P12V_SCM_FLTB_N ; B = P3V3_AUX
R1467  Q_RES  4.7K 5% EMPTY  pkg 0201LF  page 320 : A = P1V8_CPU1_RT_1D ; B = JTAG_TCK_RT_CPU1_P0
C1528  Q_CAP_DIFFBUS  DIFF BUS_0.22UF 6.3V 20% X6S  pkg C0201  page 67 : \1\ = P5E_CPU1_P3_TX_C_DN<9> ; \2\ = P5E_CPU1_P3_TX_DN<9>

(kicad_pcb
	(version 20260206)
	(generator "pcbnew")
	(generator_version "10.0")
	(general
		(thickness 1.6)
		(legacy_teardrops no)
	)
	(paper "A4")
	(title_block
		(title "04192023_DAF0TMB3IC0_F0TG_MB_C_brd_V02_OCP.brd")
		(comment 1 "Grand Teton / footprints 4212-4214 of 8354")
	)
	(layers
		(0 "F.Cu" signal "TOP")
		(4 "In1.Cu" signal "GND")
		(6 "In2.Cu" signal "IN1")
		(8 "In3.Cu" signal "GND1")
		(10 "In4.Cu" signal "IN2")
		(12 "In5.Cu" signal "GND2")
		(14 "In6.Cu" signal "IN3")
		(16 "In7.Cu" signal "GND3")
		(18 "In8.Cu" signal "VCC")
		(20 "In9.Cu" signal "VCC1")
		(22 "In10.Cu" signal "GND4")
		(24 "In11.Cu" signal "IN4")
		(26 "In12.Cu" signal "GND5")
		(28 "In13.Cu" signal "IN5")
		(30 "In14.Cu" signal "GND6")
		(32 "In15.Cu" signal "IN6")
		(34 "In16.Cu" signal "GND7")
		(2 "B.Cu" signal "BOTTOM")
		(9 "F.Adhes" user "F.Adhesive")
		(11 "B.Adhes" user "B.Adhesive")
		(13 "F.Paste" user "Package Geometry/Pastemask Top")
		(15 "B.Paste" user "Package Geometry/Pastemask Bottom")
		(5 "F.SilkS" user "Ref Des/Silkscreen Top")
		(7 "B.SilkS" user "Ref Des/Silkscreen Bottom")
		(1 "F.Mask" user "Board Geometry/Soldermask Top")
		(3 "B.Mask" user "Board Geometry/Soldermask Bottom")
		(17 "Dwgs.User" user "User.Drawings")
		(19 "Cmts.User" user "User.Comments")
		(21 "Eco1.User" user "User.Eco1")
		(23 "Eco2.User" user "User.Eco2")
		(25 "Edge.Cuts" user "Board Geometry/Outline")
		(27 "Margin" user)
		(31 "F.CrtYd" user "Package Geometry/Place Bound Top")
		(29 "B.CrtYd" user "Package Geometry/Place Bound Bottom")
		(35 "F.Fab" user "Ref Des/Assembly Top")
		(33 "B.Fab" user "Ref Des/Assembly Bottom")
	)
	(footprint ""
		(layer "F.Cu")
		(at 126.320296 -370.57203 -90)
		(property "Reference" "C1528"
			(at 0 0 270)
			(layer "F.SilkS")
			(hide yes)
			(effects
				(font
					(size 1.27 1.27)
				)
			)
		)
		(property "Value" ""
			(at 0 0 270)
			(layer "F.Fab")
			(effects
				(font
					(size 1.27 1.27)
				)
			)
		)
		(duplicate_pad_numbers_are_jumpers no)
		(fp_line
			(start -0.299974 0.150114)
			(end -0.299974 -0.150114)
			(stroke
				(width 0.1)
				(type default)
			)
			(layer "F.Fab")
		)
		(fp_line
			(start 0.299974 0.150114)
			(end -0.299974 0.150114)
			(stroke
				(width 0.1)
				(type default)
			)
			(layer "F.Fab")
		)
		(fp_line
			(start -0.299974 -0.150114)
			(end 0.299974 -0.150114)
			(stroke
				(width 0.1)
				(type default)
			)
			(layer "F.Fab")
		)
		(fp_line
			(start 0.299974 -0.150114)
			(end 0.299974 0.150114)
			(stroke
				(width 0.1)
				(type default)
			)
			(layer "F.Fab")
		)
		(pad "1" smd rect
			(at -0.2667 0 270)
			(size 0.3048 0.381)
			(layers "F.Cu" "F.Mask" "F.Paste")
			(net "P5E_CPU1_P3_TX_C_DN<9>")
		)
		(pad "2" smd rect
			(at 0.2667 0 270)
			(size 0.3048 0.381)
			(layers "F.Cu" "F.Mask" "F.Paste")
			(net "P5E_CPU1_P3_TX_DN<9>")
		)
	)
	(footprint ""
		(layer "F.Cu")
		(at 45.932344 -421.326564)
		(property "Reference" "R1467"
			(at 0 0 0)
			(layer "F.SilkS")
			(hide yes)
			(effects
				(font
					(size 1.27 1.27)
				)
			)
		)
		(property "Value" ""
			(at 0 0 0)
			(layer "F.Fab")
			(effects
				(font
					(size 1.27 1.27)
				)
			)
		)
		(duplicate_pad_numbers_are_jumpers no)
		(fp_line
			(start -0.32512 -0.175006)
			(end 0.32512 -0.175006)
			(stroke
				(width 0.1)
				(type default)
			)
			(layer "F.Fab")
		)
		(fp_line
			(start -0.32512 0.175006)
			(end -0.32512 -0.175006)
			(stroke
				(width 0.1)
				(type default)
			)
			(layer "F.Fab")
		)
		(fp_line
			(start 0.32512 -0.175006)
			(end 0.32512 0.175006)
			(stroke
				(width 0.1)
				(type default)
			)
			(layer "F.Fab")
		)
		(fp_line
			(start 0.32512 0.175006)
			(end -0.32512 0.175006)
			(stroke
				(width 0.1)
				(type default)
			)
			(layer "F.Fab")
		)
		(pad "1" smd rect
			(at -0.2667 0)
			(size 0.3048 0.381)
			(layers "F.Cu" "F.Mask" "F.Paste")
			(net "P1V8_CPU1_RT_1D")
		)
		(pad "2" smd rect
			(at 0.2667 0 180)
			(size 0.3048 0.381)
			(layers "F.Cu" "F.Mask" "F.Paste")
			(net "JTAG_TCK_RT_CPU1_P0")
		)
	)
	(footprint ""
		(layer "F.Cu")
		(at 173.216062 -30.446472 180)
		(property "Reference" "PR4007"
			(at 0 0 180)
			(layer "F.SilkS")
			(hide yes)
			(effects
				(font
					(size 1.27 1.27)
				)
			)
		)
		(property "Value" ""
			(at 0 0 180)
			(layer "F.Fab")
			(effects
				(font
					(size 1.27 1.27)
				)
			)
		)
		(duplicate_pad_numbers_are_jumpers no)
		(fp_line
			(start 0.7874 0.4064)
			(end -0.7874 0.4064)
			(stroke
				(width 0.1524)
				(type default)
			)
			(layer "F.SilkS")
		)
		(fp_line
			(start 0.7874 -0.4064)
			(end 0.7874 0.4064)
			(stroke
				(width 0.1524)
				(type default)
			)
			(layer "F.SilkS")
		)
		(fp_line
			(start -0.7874 0.4064)
			(end -0.7874 -0.4064)
			(stroke
				(width 0.1524)
				(type default)
			)
			(layer "F.SilkS")
		)
		(fp_line
			(start -0.7874 -0.4064)
			(end 0.7874 -0.4064)
			(stroke
				(width 0.1524)
				(type default)
			)
			(layer "F.SilkS")
		)
		(fp_line
			(start 0.67945 0.3048)
			(end 0.120396 0.3048)
			(stroke
				(width 0.1)
				(type default)
			)
			(layer "F.Fab")
		)
		(fp_line
			(start 0.67945 -0.3048)
			(end 0.67945 0.3048)
			(stroke
				(width 0.1)
				(type default)
			)
			(layer "F.Fab")
		)
		(fp_line
			(start 0.12065 -0.2794)
			(end 0.12065 -0.3048)
			(stroke
				(width 0.1)
				(type default)
			)
			(layer "F.Fab")
		)
		(fp_line
			(start 0.12065 -0.3048)
			(end 0.67945 -0.3048)
			(stroke
				(width 0.1)
				(type default)
			)
			(layer "F.Fab")
		)
		(fp_line
			(start 0.120396 0.3048)
			(end 0.120396 0.2794)
			(stroke
				(width 0.1)
				(type default)
			)
			(layer "F.Fab")
		)
		(fp_line
			(start 0.120396 0.2794)
			(end -0.12065 0.2794)
			(stroke
				(width 0.1)
				(type default)
			)
			(layer "F.Fab")
		)
		(fp_line
			(start -0.12065 0.3048)
			(end -0.67945 0.3048)
			(stroke
				(width 0.1)
				(type default)
			)
			(layer "F.Fab")
		)
		(fp_line
			(start -0.12065 0.2794)
			(end -0.12065 0.3048)
			(stroke
				(width 0.1)
				(type default)
			)
			(layer "F.Fab")
		)
		(fp_line
			(start -0.12065 -0.2794)
			(end 0.12065 -0.2794)
			(stroke
				(width 0.1)
				(type default)
			)
			(layer "F.Fab")
		)
		(fp_line
			(start -0.12065 -0.305054)
			(end -0.12065 -0.2794)
			(stroke
				(width 0.1)
				(type default)
			)
			(layer "F.Fab")
		)
		(fp_line
			(start -0.67945 0.3048)
			(end -0.67945 -0.305054)
			(stroke
				(width 0.1)
				(type default)
			)
			(layer "F.Fab")
		)
		(fp_line
			(start -0.67945 -0.305054)
			(end -0.12065 -0.305054)
			(stroke
				(width 0.1)
				(type default)
			)
			(layer "F.Fab")
		)
		(pad "1" smd circle
			(at -0.40005 0 180)
			(size 0 0)
			(layers "F.Cu" "F.Mask" "F.Paste")
			(net "P12V_SCM_FLTB_N")
		)
		(pad "2" smd circle
			(at 0.40005 0 180)
			(size 0 0)
			(layers "F.Cu" "F.Mask" "F.Paste")
			(net "P3V3_AUX")
		)
	)
)
